(kicad_pcb
	(version 20260206)
	(generator "pcbnew")
	(generator_version "10.0")
	(general
		(thickness 1.6)
		(legacy_teardrops no)
	)
	(paper "A4")
	(title_block
		(title "04192023_DAF0TMB3IC0_F0TG_MB_C_brd_V02_OCP.brd")
		(comment 1 "Grand Teton / footprints 1384-1390 of 8354")
	)
	(layers
		(0 "F.Cu" signal "TOP")
		(4 "In1.Cu" signal "GND")
		(6 "In2.Cu" signal "IN1")
		(8 "In3.Cu" signal "GND1")
		(10 "In4.Cu" signal "IN2")
		(12 "In5.Cu" signal "GND2")
		(14 "In6.Cu" signal "IN3")
		(16 "In7.Cu" signal "GND3")
		(18 "In8.Cu" signal "VCC")
		(20 "In9.Cu" signal "VCC1")
		(22 "In10.Cu" signal "GND4")
		(24 "In11.Cu" signal "IN4")
		(26 "In12.Cu" signal "GND5")
		(28 "In13.Cu" signal "IN5")
		(30 "In14.Cu" signal "GND6")
		(32 "In15.Cu" signal "IN6")
		(34 "In16.Cu" signal "GND7")
		(2 "B.Cu" signal "BOTTOM")
		(9 "F.Adhes" user "F.Adhesive")
		(11 "B.Adhes" user "B.Adhesive")
		(13 "F.Paste" user "Package Geometry/Pastemask Top")
		(15 "B.Paste" user "Package Geometry/Pastemask Bottom")
		(5 "F.SilkS" user "Ref Des/Silkscreen Top")
		(7 "B.SilkS" user "Ref Des/Silkscreen Bottom")
		(1 "F.Mask" user "Board Geometry/Soldermask Top")
		(3 "B.Mask" user "Board Geometry/Soldermask Bottom")
		(17 "Dwgs.User" user "User.Drawings")
		(19 "Cmts.User" user "User.Comments")
		(21 "Eco1.User" user "User.Eco1")
		(23 "Eco2.User" user "User.Eco2")
		(25 "Edge.Cuts" user "Board Geometry/Outline")
		(27 "Margin" user)
		(31 "F.CrtYd" user "Package Geometry/Place Bound Top")
		(29 "B.CrtYd" user "Package Geometry/Place Bound Bottom")
		(35 "F.Fab" user "Ref Des/Assembly Top")
		(33 "B.Fab" user "Ref Des/Assembly Bottom")
	)
	(footprint ""
		(layer "F.Cu")
		(at 92.75953 -339.886798 90)
		(property "Reference" "PC422_5"
			(at 0 0 90)
			(layer "F.SilkS")
			(hide yes)
			(effects
				(font
					(size 1.27 1.27)
				)
			)
		)
		(property "Value" ""
			(at 0 0 90)
			(layer "F.Fab")
			(effects
				(font
					(size 1.27 1.27)
				)
			)
		)
		(duplicate_pad_numbers_are_jumpers no)
		(fp_line
			(start 0.7874 -0.4064)
			(end 0.7874 0.4064)
			(stroke
				(width 0.1524)
				(type default)
			)
			(layer "F.SilkS")
		)
		(fp_line
			(start -0.7874 -0.4064)
			(end 0.7874 -0.4064)
			(stroke
				(width 0.1524)
				(type default)
			)
			(layer "F.SilkS")
		)
		(fp_line
			(start 0.7874 0.4064)
			(end -0.7874 0.4064)
			(stroke
				(width 0.1524)
				(type default)
			)
			(layer "F.SilkS")
		)
		(fp_line
			(start -0.7874 0.4064)
			(end -0.7874 -0.4064)
			(stroke
				(width 0.1524)
				(type default)
			)
			(layer "F.SilkS")
		)
		(fp_line
			(start -0.12065 -0.305054)
			(end -0.12065 -0.2794)
			(stroke
				(width 0.1)
				(type default)
			)
			(layer "F.Fab")
		)
		(fp_line
			(start -0.67945 -0.305054)
			(end -0.12065 -0.305054)
			(stroke
				(width 0.1)
				(type default)
			)
			(layer "F.Fab")
		)
		(fp_line
			(start 0.67945 -0.3048)
			(end 0.67945 0.3048)
			(stroke
				(width 0.1)
				(type default)
			)
			(layer "F.Fab")
		)
		(fp_line
			(start 0.12065 -0.3048)
			(end 0.67945 -0.3048)
			(stroke
				(width 0.1)
				(type default)
			)
			(layer "F.Fab")
		)
		(fp_line
			(start 0.12065 -0.2794)
			(end 0.12065 -0.3048)
			(stroke
				(width 0.1)
				(type default)
			)
			(layer "F.Fab")
		)
		(fp_line
			(start -0.12065 -0.2794)
			(end 0.12065 -0.2794)
			(stroke
				(width 0.1)
				(type default)
			)
			(layer "F.Fab")
		)
		(fp_line
			(start 0.120396 0.2794)
			(end -0.12065 0.2794)
			(stroke
				(width 0.1)
				(type default)
			)
			(layer "F.Fab")
		)
		(fp_line
			(start -0.12065 0.2794)
			(end -0.12065 0.3048)
			(stroke
				(width 0.1)
				(type default)
			)
			(layer "F.Fab")
		)
		(fp_line
			(start 0.67945 0.3048)
			(end 0.120396 0.3048)
			(stroke
				(width 0.1)
				(type default)
			)
			(layer "F.Fab")
		)
		(fp_line
			(start 0.120396 0.3048)
			(end 0.120396 0.2794)
			(stroke
				(width 0.1)
				(type default)
			)
			(layer "F.Fab")
		)
		(fp_line
			(start -0.12065 0.3048)
			(end -0.67945 0.3048)
			(stroke
				(width 0.1)
				(type default)
			)
			(layer "F.Fab")
		)
		(fp_line
			(start -0.67945 0.3048)
			(end -0.67945 -0.305054)
			(stroke
				(width 0.1)
				(type default)
			)
			(layer "F.Fab")
		)
		(pad "1" smd circle
			(at -0.40005 0 90)
			(size 0 0)
			(layers "F.Cu" "F.Mask" "F.Paste")
			(net "PVDDCR_CPU1_P1_VCCS")
		)
		(pad "2" smd circle
			(at 0.40005 0 90)
			(size 0 0)
			(layers "F.Cu" "F.Mask" "F.Paste")
			(net "GND")
		)
	)
	(footprint ""
		(layer "F.Cu")
		(at 446.776602 -428.61611 90)
		(property "Reference" "PC6606"
			(at 0 0 90)
			(layer "F.SilkS")
			(hide yes)
			(effects
				(font
					(size 1.27 1.27)
				)
			)
		)
		(property "Value" ""
			(at 0 0 90)
			(layer "F.Fab")
			(effects
				(font
					(size 1.27 1.27)
				)
			)
		)
		(duplicate_pad_numbers_are_jumpers no)
		(fp_line
			(start 0.7874 -0.4064)
			(end 0.7874 0.4064)
			(stroke
				(width 0.1524)
				(type default)
			)
			(layer "F.SilkS")
		)
		(fp_line
			(start -0.7874 -0.4064)
			(end 0.7874 -0.4064)
			(stroke
				(width 0.1524)
				(type default)
			)
			(layer "F.SilkS")
		)
		(fp_line
			(start 0.7874 0.4064)
			(end -0.7874 0.4064)
			(stroke
				(width 0.1524)
				(type default)
			)
			(layer "F.SilkS")
		)
		(fp_line
			(start -0.7874 0.4064)
			(end -0.7874 -0.4064)
			(stroke
				(width 0.1524)
				(type default)
			)
			(layer "F.SilkS")
		)
		(fp_line
			(start -0.12065 -0.305054)
			(end -0.12065 -0.2794)
			(stroke
				(width 0.1)
				(type default)
			)
			(layer "F.Fab")
		)
		(fp_line
			(start -0.67945 -0.305054)
			(end -0.12065 -0.305054)
			(stroke
				(width 0.1)
				(type default)
			)
			(layer "F.Fab")
		)
		(fp_line
			(start 0.67945 -0.3048)
			(end 0.67945 0.3048)
			(stroke
				(width 0.1)
				(type default)
			)
			(layer "F.Fab")
		)
		(fp_line
			(start 0.12065 -0.3048)
			(end 0.67945 -0.3048)
			(stroke
				(width 0.1)
				(type default)
			)
			(layer "F.Fab")
		)
		(fp_line
			(start 0.12065 -0.2794)
			(end 0.12065 -0.3048)
			(stroke
				(width 0.1)
				(type default)
			)
			(layer "F.Fab")
		)
		(fp_line
			(start -0.12065 -0.2794)
			(end 0.12065 -0.2794)
			(stroke
				(width 0.1)
				(type default)
			)
			(layer "F.Fab")
		)
		(fp_line
			(start 0.120396 0.2794)
			(end -0.12065 0.2794)
			(stroke
				(width 0.1)
				(type default)
			)
			(layer "F.Fab")
		)
		(fp_line
			(start -0.12065 0.2794)
			(end -0.12065 0.3048)
			(stroke
				(width 0.1)
				(type default)
			)
			(layer "F.Fab")
		)
		(fp_line
			(start 0.67945 0.3048)
			(end 0.120396 0.3048)
			(stroke
				(width 0.1)
				(type default)
			)
			(layer "F.Fab")
		)
		(fp_line
			(start 0.120396 0.3048)
			(end 0.120396 0.2794)
			(stroke
				(width 0.1)
				(type default)
			)
			(layer "F.Fab")
		)
		(fp_line
			(start -0.12065 0.3048)
			(end -0.67945 0.3048)
			(stroke
				(width 0.1)
				(type default)
			)
			(layer "F.Fab")
		)
		(fp_line
			(start -0.67945 0.3048)
			(end -0.67945 -0.305054)
			(stroke
				(width 0.1)
				(type default)
			)
			(layer "F.Fab")
		)
		(pad "1" smd circle
			(at -0.40005 0 90)
			(size 0 0)
			(layers "F.Cu" "F.Mask" "F.Paste")
			(net "PV09_RETIMER_CPU0_VCCS")
		)
		(pad "2" smd circle
			(at 0.40005 0 90)
			(size 0 0)
			(layers "F.Cu" "F.Mask" "F.Paste")
			(net "GND")
		)
	)
	(footprint ""
		(layer "F.Cu")
		(at 111.251238 -41.17975 -90)
		(property "Reference" "R6294"
			(at 0 0 270)
			(layer "F.SilkS")
			(hide yes)
			(effects
				(font
					(size 1.27 1.27)
				)
			)
		)
		(property "Value" ""
			(at 0 0 270)
			(layer "F.Fab")
			(effects
				(font
					(size 1.27 1.27)
				)
			)
		)
		(duplicate_pad_numbers_are_jumpers no)
		(fp_line
			(start -0.7874 0.4064)
			(end -0.7874 -0.4064)
			(stroke
				(width 0.1524)
				(type default)
			)
			(layer "F.SilkS")
		)
		(fp_line
			(start 0.7874 0.4064)
			(end -0.7874 0.4064)
			(stroke
				(width 0.1524)
				(type default)
			)
			(layer "F.SilkS")
		)
		(fp_line
			(start -0.7874 -0.4064)
			(end 0.7874 -0.4064)
			(stroke
				(width 0.1524)
				(type default)
			)
			(layer "F.SilkS")
		)
		(fp_line
			(start 0.7874 -0.4064)
			(end 0.7874 0.4064)
			(stroke
				(width 0.1524)
				(type default)
			)
			(layer "F.SilkS")
		)
		(fp_line
			(start -0.67945 0.3048)
			(end -0.67945 -0.305054)
			(stroke
				(width 0.1)
				(type default)
			)
			(layer "F.Fab")
		)
		(fp_line
			(start -0.12065 0.3048)
			(end -0.67945 0.3048)
			(stroke
				(width 0.1)
				(type default)
			)
			(layer "F.Fab")
		)
		(fp_line
			(start 0.120396 0.3048)
			(end 0.120396 0.2794)
			(stroke
				(width 0.1)
				(type default)
			)
			(layer "F.Fab")
		)
		(fp_line
			(start 0.67945 0.3048)
			(end 0.120396 0.3048)
			(stroke
				(width 0.1)
				(type default)
			)
			(layer "F.Fab")
		)
		(fp_line
			(start -0.12065 0.2794)
			(end -0.12065 0.3048)
			(stroke
				(width 0.1)
				(type default)
			)
			(layer "F.Fab")
		)
		(fp_line
			(start 0.120396 0.2794)
			(end -0.12065 0.2794)
			(stroke
				(width 0.1)
				(type default)
			)
			(layer "F.Fab")
		)
		(fp_line
			(start -0.12065 -0.2794)
			(end 0.12065 -0.2794)
			(stroke
				(width 0.1)
				(type default)
			)
			(layer "F.Fab")
		)
		(fp_line
			(start 0.12065 -0.2794)
			(end 0.12065 -0.3048)
			(stroke
				(width 0.1)
				(type default)
			)
			(layer "F.Fab")
		)
		(fp_line
			(start 0.12065 -0.3048)
			(end 0.67945 -0.3048)
			(stroke
				(width 0.1)
				(type default)
			)
			(layer "F.Fab")
		)
		(fp_line
			(start 0.67945 -0.3048)
			(end 0.67945 0.3048)
			(stroke
				(width 0.1)
				(type default)
			)
			(layer "F.Fab")
		)
		(fp_line
			(start -0.67945 -0.305054)
			(end -0.12065 -0.305054)
			(stroke
				(width 0.1)
				(type default)
			)
			(layer "F.Fab")
		)
		(fp_line
			(start -0.12065 -0.305054)
			(end -0.12065 -0.2794)
			(stroke
				(width 0.1)
				(type default)
			)
			(layer "F.Fab")
		)
		(pad "1" smd circle
			(at -0.40005 0 270)
			(size 0 0)
			(layers "F.Cu" "F.Mask" "F.Paste")
			(net "P3V3_AUX")
		)
		(pad "2" smd circle
			(at 0.40005 0 270)
			(size 0 0)
			(layers "F.Cu" "F.Mask" "F.Paste")
			(net "USB_HUB2_MRP_I2C_SLV_CFG0")
		)
	)
	(footprint ""
		(layer "F.Cu")
		(at 272.507202 -363.010704)
		(property "Reference" "JP6500"
			(at -1.4097 -2.009648 0)
			(unlocked yes)
			(layer "F.SilkS")
			(effects
				(font
					(size 0.7874 0.5842)
					(thickness 0.1524)
				)
				(justify left)
			)
		)
		(property "Value" ""
			(at 0 0 0)
			(layer "F.Fab")
			(effects
				(font
					(size 1.27 1.27)
				)
			)
		)
		(duplicate_pad_numbers_are_jumpers no)
		(fp_line
			(start -1.249934 -1.320038)
			(end 1.249934 -1.320038)
			(stroke
				(width 0.1524)
				(type default)
			)
			(layer "F.SilkS")
		)
		(fp_line
			(start -1.249934 6.400038)
			(end -1.249934 -1.320038)
			(stroke
				(width 0.1524)
				(type default)
			)
			(layer "F.SilkS")
		)
		(fp_line
			(start 1.249934 -1.320038)
			(end 1.249934 6.400038)
			(stroke
				(width 0.1524)
				(type default)
			)
			(layer "F.SilkS")
		)
		(fp_line
			(start 1.249934 6.400038)
			(end -1.249934 6.400038)
			(stroke
				(width 0.1524)
				(type default)
			)
			(layer "F.SilkS")
		)
		(fp_poly
			(pts
				(xy -2.5654 -0.556514) (xy -1.452372 0) (xy -2.5654 0.556514)
			)
			(stroke
				(width 0)
				(type default)
			)
			(fill yes)
			(layer "F.SilkS")
		)
		(fp_line
			(start -1.249934 -1.320038)
			(end 1.249934 -1.320038)
			(stroke
				(width 0.1)
				(type default)
			)
			(layer "F.Fab")
		)
		(fp_line
			(start -1.249934 6.400038)
			(end -1.249934 -1.320038)
			(stroke
				(width 0.1)
				(type default)
			)
			(layer "F.Fab")
		)
		(fp_line
			(start 1.249934 -1.320038)
			(end 1.249934 6.400038)
			(stroke
				(width 0.1)
				(type default)
			)
			(layer "F.Fab")
		)
		(fp_line
			(start 1.249934 6.400038)
			(end -1.249934 6.400038)
			(stroke
				(width 0.1)
				(type default)
			)
			(layer "F.Fab")
		)
		(fp_poly
			(pts
				(xy -2.5654 -0.556514) (xy -1.452372 0) (xy -2.5654 0.556514)
			)
			(stroke
				(width 0)
				(type default)
			)
			(fill yes)
			(layer "F.Fab")
		)
		(fp_text user "3"
			(at -1.778 5.13207 0)
			(unlocked yes)
			(layer "F.SilkS")
			(effects
				(font
					(size 0.7874 0.5842)
					(thickness 0.1524)
				)
			)
		)
		(fp_text user "3"
			(at -1.1557 5.18287 0)
			(unlocked yes)
			(layer "B.SilkS")
			(effects
				(font
					(size 0.7874 0.5842)
					(thickness 0.1524)
				)
				(justify mirror)
			)
		)
		(fp_text user "1"
			(at -1.143 0.02667 0)
			(unlocked yes)
			(layer "B.SilkS")
			(effects
				(font
					(size 0.7874 0.5842)
					(thickness 0.1524)
				)
				(justify mirror)
			)
		)
		(fp_text user "3"
			(at -1.1557 5.18287 0)
			(unlocked yes)
			(layer "B.Fab")
			(effects
				(font
					(size 0.7874 0.5842)
					(thickness 0.1524)
				)
				(justify mirror)
			)
		)
		(fp_text user "1"
			(at -1.143 0.02667 0)
			(unlocked yes)
			(layer "B.Fab")
			(effects
				(font
					(size 0.7874 0.5842)
					(thickness 0.1524)
				)
				(justify mirror)
			)
		)
		(fp_text user "3"
			(at -1.778 5.13207 0)
			(unlocked yes)
			(layer "F.Fab")
			(effects
				(font
					(size 0.7874 0.5842)
					(thickness 0.1524)
				)
			)
		)
		(pad "1" thru_hole rect
			(at 0 0)
			(size 1.5494 1.5494)
			(drill 1.0414)
			(layers "*.Cu" "*.Mask")
			(remove_unused_layers no)
			(net "SMB_MUX_RT_R2_SCL")
			(clearance 0)
			(padstack
				(mode front_inner_back)
				(layer "Inner"
					(shape circle)
					(size 1.5494 1.5494)
					(clearance 0)
				)
				(layer "B.Cu"
					(shape rect)
					(size 1.5494 1.5494)
					(clearance 0)
				)
			)
		)
		(pad "2" thru_hole circle
			(at 0 2.54)
			(size 1.5494 1.5494)
			(drill 1.0414)
			(layers "*.Cu" "*.Mask")
			(remove_unused_layers no)
			(net "SMB_MUX_RT_R2_SDA")
			(clearance 0)
		)
		(pad "3" thru_hole circle
			(at 0 5.08)
			(size 1.5494 1.5494)
			(drill 1.0414)
			(layers "*.Cu" "*.Mask")
			(remove_unused_layers no)
			(net "GND")
			(clearance 0)
		)
	)
	(footprint ""
		(layer "F.Cu")
		(at 358.268524 -388.767828)
		(property "Reference" "C934"
			(at 0 0 0)
			(layer "F.SilkS")
			(hide yes)
			(effects
				(font
					(size 1.27 1.27)
				)
			)
		)
		(property "Value" ""
			(at 0 0 0)
			(layer "F.Fab")
			(effects
				(font
					(size 1.27 1.27)
				)
			)
		)
		(duplicate_pad_numbers_are_jumpers no)
		(fp_line
			(start -0.299974 -0.150114)
			(end 0.299974 -0.150114)
			(stroke
				(width 0.1)
				(type default)
			)
			(layer "F.Fab")
		)
		(fp_line
			(start -0.299974 0.150114)
			(end -0.299974 -0.150114)
			(stroke
				(width 0.1)
				(type default)
			)
			(layer "F.Fab")
		)
		(fp_line
			(start 0.299974 -0.150114)
			(end 0.299974 0.150114)
			(stroke
				(width 0.1)
				(type default)
			)
			(layer "F.Fab")
		)
		(fp_line
			(start 0.299974 0.150114)
			(end -0.299974 0.150114)
			(stroke
				(width 0.1)
				(type default)
			)
			(layer "F.Fab")
		)
		(pad "1" smd rect
			(at -0.2667 0)
			(size 0.3048 0.381)
			(layers "F.Cu" "F.Mask" "F.Paste")
			(net "P5E_CPU0_P1_TX_C_DN<15>")
		)
		(pad "2" smd rect
			(at 0.2667 0)
			(size 0.3048 0.381)
			(layers "F.Cu" "F.Mask" "F.Paste")
			(net "P5E_CPU0_P1_TX_DN<15>")
		)
	)
	(footprint ""
		(layer "F.Cu")
		(at 310.809386 -416.899344 -90)
		(property "Reference" "C6505"
			(at 0 0 270)
			(layer "F.SilkS")
			(hide yes)
			(effects
				(font
					(size 1.27 1.27)
				)
			)
		)
		(property "Value" ""
			(at 0 0 270)
			(layer "F.Fab")
			(effects
				(font
					(size 1.27 1.27)
				)
			)
		)
		(duplicate_pad_numbers_are_jumpers no)
		(fp_line
			(start -0.299974 0.150114)
			(end -0.299974 -0.150114)
			(stroke
				(width 0.1)
				(type default)
			)
			(layer "F.Fab")
		)
		(fp_line
			(start 0.299974 0.150114)
			(end -0.299974 0.150114)
			(stroke
				(width 0.1)
				(type default)
			)
			(layer "F.Fab")
		)
		(fp_line
			(start -0.299974 -0.150114)
			(end 0.299974 -0.150114)
			(stroke
				(width 0.1)
				(type default)
			)
			(layer "F.Fab")
		)
		(fp_line
			(start 0.299974 -0.150114)
			(end 0.299974 0.150114)
			(stroke
				(width 0.1)
				(type default)
			)
			(layer "F.Fab")
		)
		(pad "1" smd rect
			(at -0.2667 0 270)
			(size 0.3048 0.381)
			(layers "F.Cu" "F.Mask" "F.Paste")
			(net "P5E_CPU0_P0_TX_BUF_C_DP<2>")
		)
		(pad "2" smd rect
			(at 0.2667 0 270)
			(size 0.3048 0.381)
			(layers "F.Cu" "F.Mask" "F.Paste")
			(net "P5E_CPU0_P0_TX_BUF_DP<2>")
		)
	)
	(footprint ""
		(layer "F.Cu")
		(at 283.265118 -426.20565 -90)
		(property "Reference" "R4493"
			(at 0 0 270)
			(layer "F.SilkS")
			(hide yes)
			(effects
				(font
					(size 1.27 1.27)
				)
			)
		)
		(property "Value" ""
			(at 0 0 270)
			(layer "F.Fab")
			(effects
				(font
					(size 1.27 1.27)
				)
			)
		)
		(duplicate_pad_numbers_are_jumpers no)
		(fp_line
			(start -1.2954 0.5842)
			(end -1.2954 -0.5842)
			(stroke
				(width 0.1524)
				(type default)
			)
			(layer "F.SilkS")
		)
		(fp_line
			(start 1.2954 0.5842)
			(end -1.2954 0.5842)
			(stroke
				(width 0.1524)
				(type default)
			)
			(layer "F.SilkS")
		)
		(fp_line
			(start -1.2954 -0.5842)
			(end 1.2954 -0.5842)
			(stroke
				(width 0.1524)
				(type default)
			)
			(layer "F.SilkS")
		)
		(fp_line
			(start 1.2954 -0.5842)
			(end 1.2954 0.5842)
			(stroke
				(width 0.1524)
				(type default)
			)
			(layer "F.SilkS")
		)
		(fp_line
			(start -0.8636 0.4572)
			(end -0.8636 0.4318)
			(stroke
				(width 0.1)
				(type default)
			)
			(layer "F.Fab")
		)
		(fp_line
			(start 0.8636 0.4572)
			(end -0.8636 0.4572)
			(stroke
				(width 0.1)
				(type default)
			)
			(layer "F.Fab")
		)
		(fp_line
			(start -0.8636 0.4318)
			(end -0.8636 0.4064)
			(stroke
				(width 0.1)
				(type default)
			)
			(layer "F.Fab")
		)
		(fp_line
			(start -1.1938 0.4064)
			(end -1.1938 -0.406654)
			(stroke
				(width 0.1)
				(type default)
			)
			(layer "F.Fab")
		)
		(fp_line
			(start -0.8636 0.4064)
			(end -1.1938 0.4064)
			(stroke
				(width 0.1)
				(type default)
			)
			(layer "F.Fab")
		)
		(fp_line
			(start 0.8636 0.4064)
			(end 0.8636 0.4572)
			(stroke
				(width 0.1)
				(type default)
			)
			(layer "F.Fab")
		)
		(fp_line
			(start 1.1938 0.4064)
			(end 0.8636 0.4064)
			(stroke
				(width 0.1)
				(type default)
			)
			(layer "F.Fab")
		)
		(fp_line
			(start -1.1938 -0.406654)
			(end -0.8636 -0.406654)
			(stroke
				(width 0.1)
				(type default)
			)
			(layer "F.Fab")
		)
		(fp_line
			(start -0.8636 -0.406654)
			(end -0.8636 -0.4572)
			(stroke
				(width 0.1)
				(type default)
			)
			(layer "F.Fab")
		)
		(fp_line
			(start 0.8636 -0.406654)
			(end 1.1938 -0.406654)
			(stroke
				(width 0.1)
				(type default)
			)
			(layer "F.Fab")
		)
		(fp_line
			(start 1.1938 -0.406654)
			(end 1.1938 0.4064)
			(stroke
				(width 0.1)
				(type default)
			)
			(layer "F.Fab")
		)
		(fp_line
			(start -0.8636 -0.4572)
			(end 0.8636 -0.4572)
			(stroke
				(width 0.1)
				(type default)
			)
			(layer "F.Fab")
		)
		(fp_line
			(start 0.8636 -0.4572)
			(end 0.8636 -0.406654)
			(stroke
				(width 0.1)
				(type default)
			)
			(layer "F.Fab")
		)
		(pad "1" smd rect
			(at -0.7366 0 180)
			(size 0.7112 0.8128)
			(layers "F.Cu" "F.Mask" "F.Paste")
			(net "P3V3_9ZXL045_P0")
		)
		(pad "2" smd rect
			(at 0.7366 0 180)
			(size 0.7112 0.8128)
			(layers "F.Cu" "F.Mask" "F.Paste")
			(net "P3V3_9ZXL045_P0_VDDA")
		)
	)
)
